(kicad_pcb
	(version 20260206)
	(generator "pcbnew")
	(generator_version "10.0")
	(general
		(thickness 1.6)
		(legacy_teardrops no)
	)
	(paper "A4")
	(title_block
		(title "01162023_DA0F0TEBIF0_F0T_Expander_BD_F_brd_V02_OCP.brd")
		(comment 1 "Grand Teton / footprints 9169-9176 of 9728")
	)
	(layers
		(0 "F.Cu" signal "TOP")
		(4 "In1.Cu" signal "GND")
		(6 "In2.Cu" signal "VCC")
		(8 "In3.Cu" signal "VCC1")
		(10 "In4.Cu" signal "GND1")
		(12 "In5.Cu" signal "IN1")
		(14 "In6.Cu" signal "GND2")
		(16 "In7.Cu" signal "IN2")
		(18 "In8.Cu" signal "GND3")
		(20 "In9.Cu" signal "IN3")
		(22 "In10.Cu" signal "GND4")
		(24 "In11.Cu" signal "IN4")
		(26 "In12.Cu" signal "GND5")
		(28 "In13.Cu" signal "IN5")
		(30 "In14.Cu" signal "GND6")
		(32 "In15.Cu" signal "IN6")
		(34 "In16.Cu" signal "GND7")
		(2 "B.Cu" signal "BOTTOM")
		(9 "F.Adhes" user "F.Adhesive")
		(11 "B.Adhes" user "B.Adhesive")
		(13 "F.Paste" user "Package Geometry/Pastemask Top")
		(15 "B.Paste" user "Package Geometry/Pastemask Bottom")
		(5 "F.SilkS" user "Ref Des/Silkscreen Top")
		(7 "B.SilkS" user "Ref Des/Silkscreen Bottom")
		(1 "F.Mask" user "Board Geometry/Soldermask Top")
		(3 "B.Mask" user "Board Geometry/Soldermask Bottom")
		(17 "Dwgs.User" user "User.Drawings")
		(19 "Cmts.User" user "User.Comments")
		(21 "Eco1.User" user "User.Eco1")
		(23 "Eco2.User" user "User.Eco2")
		(25 "Edge.Cuts" user "Board Geometry/Outline")
		(27 "Margin" user)
		(31 "F.CrtYd" user "Package Geometry/Place Bound Top")
		(29 "B.CrtYd" user "Package Geometry/Place Bound Bottom")
		(35 "F.Fab" user "Ref Des/Assembly Top")
		(33 "B.Fab" user "Ref Des/Assembly Bottom")
	)
	(footprint ""
		(layer "B.Cu")
		(at 23.212298 -228.346 90)
		(property "Reference" "R3445"
			(at 0 0 90)
			(layer "B.SilkS")
			(hide yes)
			(effects
				(font
					(size 1.27 1.27)
				)
				(justify mirror)
			)
		)
		(property "Value" ""
			(at 0 0 90)
			(layer "B.Fab")
			(effects
				(font
					(size 1.27 1.27)
				)
				(justify mirror)
			)
		)
		(duplicate_pad_numbers_are_jumpers no)
		(fp_line
			(start 0.7874 -0.4064)
			(end -0.7874 -0.4064)
			(stroke
				(width 0.1524)
				(type default)
			)
			(layer "B.SilkS")
		)
		(fp_line
			(start -0.7874 -0.4064)
			(end -0.7874 0.4064)
			(stroke
				(width 0.1524)
				(type default)
			)
			(layer "B.SilkS")
		)
		(fp_line
			(start 0.7874 0.4064)
			(end 0.7874 -0.4064)
			(stroke
				(width 0.1524)
				(type default)
			)
			(layer "B.SilkS")
		)
		(fp_line
			(start -0.7874 0.4064)
			(end 0.7874 0.4064)
			(stroke
				(width 0.1524)
				(type default)
			)
			(layer "B.SilkS")
		)
		(fp_line
			(start 0.67945 -0.305054)
			(end 0.12065 -0.305054)
			(stroke
				(width 0.1)
				(type default)
			)
			(layer "B.Fab")
		)
		(fp_line
			(start 0.12065 -0.305054)
			(end 0.12065 -0.2794)
			(stroke
				(width 0.1)
				(type default)
			)
			(layer "B.Fab")
		)
		(fp_line
			(start -0.12065 -0.3048)
			(end -0.67945 -0.3048)
			(stroke
				(width 0.1)
				(type default)
			)
			(layer "B.Fab")
		)
		(fp_line
			(start -0.67945 -0.3048)
			(end -0.67945 0.3048)
			(stroke
				(width 0.1)
				(type default)
			)
			(layer "B.Fab")
		)
		(fp_line
			(start 0.12065 -0.2794)
			(end -0.12065 -0.2794)
			(stroke
				(width 0.1)
				(type default)
			)
			(layer "B.Fab")
		)
		(fp_line
			(start -0.12065 -0.2794)
			(end -0.12065 -0.3048)
			(stroke
				(width 0.1)
				(type default)
			)
			(layer "B.Fab")
		)
		(fp_line
			(start 0.12065 0.2794)
			(end 0.12065 0.3048)
			(stroke
				(width 0.1)
				(type default)
			)
			(layer "B.Fab")
		)
		(fp_line
			(start -0.120396 0.2794)
			(end 0.12065 0.2794)
			(stroke
				(width 0.1)
				(type default)
			)
			(layer "B.Fab")
		)
		(fp_line
			(start 0.67945 0.3048)
			(end 0.67945 -0.305054)
			(stroke
				(width 0.1)
				(type default)
			)
			(layer "B.Fab")
		)
		(fp_line
			(start 0.12065 0.3048)
			(end 0.67945 0.3048)
			(stroke
				(width 0.1)
				(type default)
			)
			(layer "B.Fab")
		)
		(fp_line
			(start -0.120396 0.3048)
			(end -0.120396 0.2794)
			(stroke
				(width 0.1)
				(type default)
			)
			(layer "B.Fab")
		)
		(fp_line
			(start -0.67945 0.3048)
			(end -0.120396 0.3048)
			(stroke
				(width 0.1)
				(type default)
			)
			(layer "B.Fab")
		)
		(pad "1" smd circle
			(at 0.40005 0 270)
			(size 0 0)
			(layers "B.Cu" "B.Mask" "B.Paste")
			(net "SPI_PEX0_SDIO1_MUX_R")
		)
		(pad "2" smd circle
			(at -0.40005 0 270)
			(size 0 0)
			(layers "B.Cu" "B.Mask" "B.Paste")
			(net "SPI_PEX0_SDIO1_MUX")
		)
	)
	(footprint ""
		(layer "B.Cu")
		(at 276.93366 -390.463278)
		(property "Reference" "PR6618"
			(at 0 0 0)
			(layer "B.SilkS")
			(hide yes)
			(effects
				(font
					(size 1.27 1.27)
				)
				(justify mirror)
			)
		)
		(property "Value" ""
			(at 0 0 0)
			(layer "B.Fab")
			(effects
				(font
					(size 1.27 1.27)
				)
				(justify mirror)
			)
		)
		(duplicate_pad_numbers_are_jumpers no)
		(fp_line
			(start -0.7874 -0.4064)
			(end -0.7874 0.4064)
			(stroke
				(width 0.1524)
				(type default)
			)
			(layer "B.SilkS")
		)
		(fp_line
			(start -0.7874 0.4064)
			(end 0.7874 0.4064)
			(stroke
				(width 0.1524)
				(type default)
			)
			(layer "B.SilkS")
		)
		(fp_line
			(start 0.7874 -0.4064)
			(end -0.7874 -0.4064)
			(stroke
				(width 0.1524)
				(type default)
			)
			(layer "B.SilkS")
		)
		(fp_line
			(start 0.7874 0.4064)
			(end 0.7874 -0.4064)
			(stroke
				(width 0.1524)
				(type default)
			)
			(layer "B.SilkS")
		)
		(fp_line
			(start -0.67945 -0.3048)
			(end -0.67945 0.3048)
			(stroke
				(width 0.1)
				(type default)
			)
			(layer "B.Fab")
		)
		(fp_line
			(start -0.67945 0.3048)
			(end -0.120396 0.3048)
			(stroke
				(width 0.1)
				(type default)
			)
			(layer "B.Fab")
		)
		(fp_line
			(start -0.12065 -0.3048)
			(end -0.67945 -0.3048)
			(stroke
				(width 0.1)
				(type default)
			)
			(layer "B.Fab")
		)
		(fp_line
			(start -0.12065 -0.2794)
			(end -0.12065 -0.3048)
			(stroke
				(width 0.1)
				(type default)
			)
			(layer "B.Fab")
		)
		(fp_line
			(start -0.120396 0.2794)
			(end 0.12065 0.2794)
			(stroke
				(width 0.1)
				(type default)
			)
			(layer "B.Fab")
		)
		(fp_line
			(start -0.120396 0.3048)
			(end -0.120396 0.2794)
			(stroke
				(width 0.1)
				(type default)
			)
			(layer "B.Fab")
		)
		(fp_line
			(start 0.12065 -0.305054)
			(end 0.12065 -0.2794)
			(stroke
				(width 0.1)
				(type default)
			)
			(layer "B.Fab")
		)
		(fp_line
			(start 0.12065 -0.2794)
			(end -0.12065 -0.2794)
			(stroke
				(width 0.1)
				(type default)
			)
			(layer "B.Fab")
		)
		(fp_line
			(start 0.12065 0.2794)
			(end 0.12065 0.3048)
			(stroke
				(width 0.1)
				(type default)
			)
			(layer "B.Fab")
		)
		(fp_line
			(start 0.12065 0.3048)
			(end 0.67945 0.3048)
			(stroke
				(width 0.1)
				(type default)
			)
			(layer "B.Fab")
		)
		(fp_line
			(start 0.67945 -0.305054)
			(end 0.12065 -0.305054)
			(stroke
				(width 0.1)
				(type default)
			)
			(layer "B.Fab")
		)
		(fp_line
			(start 0.67945 0.3048)
			(end 0.67945 -0.305054)
			(stroke
				(width 0.1)
				(type default)
			)
			(layer "B.Fab")
		)
		(pad "1" smd circle
			(at 0.40005 0 180)
			(size 0 0)
			(layers "B.Cu" "B.Mask" "B.Paste")
			(net "LTC4282_ALERT1_R_N")
		)
		(pad "2" smd circle
			(at -0.40005 0 180)
			(size 0 0)
			(layers "B.Cu" "B.Mask" "B.Paste")
			(net "HSC_ALERT1_R_N")
		)
	)
	(footprint ""
		(layer "B.Cu")
		(at 162.4457 -293.52494)
		(property "Reference" "C3231"
			(at 0 0 0)
			(layer "B.SilkS")
			(hide yes)
			(effects
				(font
					(size 1.27 1.27)
				)
				(justify mirror)
			)
		)
		(property "Value" ""
			(at 0 0 0)
			(layer "B.Fab")
			(effects
				(font
					(size 1.27 1.27)
				)
				(justify mirror)
			)
		)
		(duplicate_pad_numbers_are_jumpers no)
		(fp_line
			(start -0.299974 -0.150114)
			(end -0.299974 0.150114)
			(stroke
				(width 0.1)
				(type default)
			)
			(layer "B.Fab")
		)
		(fp_line
			(start -0.299974 0.150114)
			(end 0.299974 0.150114)
			(stroke
				(width 0.1)
				(type default)
			)
			(layer "B.Fab")
		)
		(fp_line
			(start 0.299974 -0.150114)
			(end -0.299974 -0.150114)
			(stroke
				(width 0.1)
				(type default)
			)
			(layer "B.Fab")
		)
		(fp_line
			(start 0.299974 0.150114)
			(end 0.299974 -0.150114)
			(stroke
				(width 0.1)
				(type default)
			)
			(layer "B.Fab")
		)
		(pad "1" smd rect
			(at 0.2667 0 180)
			(size 0.3048 0.381)
			(layers "B.Cu" "B.Mask" "B.Paste")
			(net "PCEPLL6_VDDA18_PEX1")
		)
		(pad "2" smd rect
			(at -0.2667 0 180)
			(size 0.3048 0.381)
			(layers "B.Cu" "B.Mask" "B.Paste")
			(net "GND")
		)
	)
	(footprint ""
		(layer "B.Cu")
		(at 184.29986 -293.52494 180)
		(property "Reference" "C1358"
			(at 0 0 0)
			(layer "B.SilkS")
			(hide yes)
			(effects
				(font
					(size 1.27 1.27)
				)
				(justify mirror)
			)
		)
		(property "Value" ""
			(at 0 0 0)
			(layer "B.Fab")
			(effects
				(font
					(size 1.27 1.27)
				)
				(justify mirror)
			)
		)
		(duplicate_pad_numbers_are_jumpers no)
		(fp_line
			(start 0.299974 0.150114)
			(end 0.299974 -0.150114)
			(stroke
				(width 0.1)
				(type default)
			)
			(layer "B.Fab")
		)
		(fp_line
			(start 0.299974 -0.150114)
			(end -0.299974 -0.150114)
			(stroke
				(width 0.1)
				(type default)
			)
			(layer "B.Fab")
		)
		(fp_line
			(start -0.299974 0.150114)
			(end 0.299974 0.150114)
			(stroke
				(width 0.1)
				(type default)
			)
			(layer "B.Fab")
		)
		(fp_line
			(start -0.299974 -0.150114)
			(end -0.299974 0.150114)
			(stroke
				(width 0.1)
				(type default)
			)
			(layer "B.Fab")
		)
		(pad "1" smd rect
			(at 0.2667 0)
			(size 0.3048 0.381)
			(layers "B.Cu" "B.Mask" "B.Paste")
			(net "P0V8_PEX1")
		)
		(pad "2" smd rect
			(at -0.2667 0)
			(size 0.3048 0.381)
			(layers "B.Cu" "B.Mask" "B.Paste")
			(net "GND")
		)
	)
	(footprint ""
		(layer "B.Cu")
		(at 109.245654 -308.580028 90)
		(property "Reference" "C4193"
			(at 0 0 90)
			(layer "B.SilkS")
			(hide yes)
			(effects
				(font
					(size 1.27 1.27)
				)
				(justify mirror)
			)
		)
		(property "Value" ""
			(at 0 0 90)
			(layer "B.Fab")
			(effects
				(font
					(size 1.27 1.27)
				)
				(justify mirror)
			)
		)
		(duplicate_pad_numbers_are_jumpers no)
		(fp_line
			(start 1.2954 -0.5842)
			(end -1.2954 -0.5842)
			(stroke
				(width 0.1524)
				(type default)
			)
			(layer "B.SilkS")
		)
		(fp_line
			(start -1.2954 -0.5842)
			(end -1.2954 0.5842)
			(stroke
				(width 0.1524)
				(type default)
			)
			(layer "B.SilkS")
		)
		(fp_line
			(start 1.2954 0.5842)
			(end 1.2954 -0.5842)
			(stroke
				(width 0.1524)
				(type default)
			)
			(layer "B.SilkS")
		)
		(fp_line
			(start -1.2954 0.5842)
			(end 1.2954 0.5842)
			(stroke
				(width 0.1524)
				(type default)
			)
			(layer "B.SilkS")
		)
		(fp_line
			(start 0.8636 -0.4572)
			(end -0.8636 -0.4572)
			(stroke
				(width 0.1)
				(type default)
			)
			(layer "B.Fab")
		)
		(fp_line
			(start -0.8636 -0.4572)
			(end -0.8636 -0.4064)
			(stroke
				(width 0.1)
				(type default)
			)
			(layer "B.Fab")
		)
		(fp_line
			(start 1.1938 -0.4064)
			(end 0.8636 -0.4064)
			(stroke
				(width 0.1)
				(type default)
			)
			(layer "B.Fab")
		)
		(fp_line
			(start 0.8636 -0.4064)
			(end 0.8636 -0.4572)
			(stroke
				(width 0.1)
				(type default)
			)
			(layer "B.Fab")
		)
		(fp_line
			(start -0.8636 -0.4064)
			(end -1.1938 -0.4064)
			(stroke
				(width 0.1)
				(type default)
			)
			(layer "B.Fab")
		)
		(fp_line
			(start -1.1938 -0.4064)
			(end -1.1938 0.4064)
			(stroke
				(width 0.1)
				(type default)
			)
			(layer "B.Fab")
		)
		(fp_line
			(start 1.1938 0.4064)
			(end 1.1938 -0.4064)
			(stroke
				(width 0.1)
				(type default)
			)
			(layer "B.Fab")
		)
		(fp_line
			(start 0.8636 0.4064)
			(end 1.1938 0.4064)
			(stroke
				(width 0.1)
				(type default)
			)
			(layer "B.Fab")
		)
		(fp_line
			(start -0.8636 0.4064)
			(end -0.8636 0.4572)
			(stroke
				(width 0.1)
				(type default)
			)
			(layer "B.Fab")
		)
		(fp_line
			(start -1.1938 0.4064)
			(end -0.8636 0.4064)
			(stroke
				(width 0.1)
				(type default)
			)
			(layer "B.Fab")
		)
		(fp_line
			(start 0.8636 0.4572)
			(end 0.8636 0.4064)
			(stroke
				(width 0.1)
				(type default)
			)
			(layer "B.Fab")
		)
		(fp_line
			(start -0.8636 0.4572)
			(end 0.8636 0.4572)
			(stroke
				(width 0.1)
				(type default)
			)
			(layer "B.Fab")
		)
		(pad "1" smd rect
			(at 0.7366 0)
			(size 0.7112 0.8128)
			(layers "B.Cu" "B.Mask" "B.Paste")
			(net "P0V8_PEX0")
		)
		(pad "2" smd rect
			(at -0.7366 0)
			(size 0.7112 0.8128)
			(layers "B.Cu" "B.Mask" "B.Paste")
			(net "GND")
		)
	)
	(footprint ""
		(layer "B.Cu")
		(at 198.280274 -368.72164 -90)
		(property "Reference" "PR14"
			(at 0 0 90)
			(layer "B.SilkS")
			(hide yes)
			(effects
				(font
					(size 1.27 1.27)
				)
				(justify mirror)
			)
		)
		(property "Value" ""
			(at 0 0 90)
			(layer "B.Fab")
			(effects
				(font
					(size 1.27 1.27)
				)
				(justify mirror)
			)
		)
		(duplicate_pad_numbers_are_jumpers no)
		(fp_line
			(start -0.7874 0.4064)
			(end 0.7874 0.4064)
			(stroke
				(width 0.1524)
				(type default)
			)
			(layer "B.SilkS")
		)
		(fp_line
			(start 0.7874 0.4064)
			(end 0.7874 -0.4064)
			(stroke
				(width 0.1524)
				(type default)
			)
			(layer "B.SilkS")
		)
		(fp_line
			(start -0.7874 -0.4064)
			(end -0.7874 0.4064)
			(stroke
				(width 0.1524)
				(type default)
			)
			(layer "B.SilkS")
		)
		(fp_line
			(start 0.7874 -0.4064)
			(end -0.7874 -0.4064)
			(stroke
				(width 0.1524)
				(type default)
			)
			(layer "B.SilkS")
		)
		(fp_line
			(start -0.67945 0.3048)
			(end -0.120396 0.3048)
			(stroke
				(width 0.1)
				(type default)
			)
			(layer "B.Fab")
		)
		(fp_line
			(start -0.120396 0.3048)
			(end -0.120396 0.2794)
			(stroke
				(width 0.1)
				(type default)
			)
			(layer "B.Fab")
		)
		(fp_line
			(start 0.12065 0.3048)
			(end 0.67945 0.3048)
			(stroke
				(width 0.1)
				(type default)
			)
			(layer "B.Fab")
		)
		(fp_line
			(start 0.67945 0.3048)
			(end 0.67945 -0.305054)
			(stroke
				(width 0.1)
				(type default)
			)
			(layer "B.Fab")
		)
		(fp_line
			(start -0.120396 0.2794)
			(end 0.12065 0.2794)
			(stroke
				(width 0.1)
				(type default)
			)
			(layer "B.Fab")
		)
		(fp_line
			(start 0.12065 0.2794)
			(end 0.12065 0.3048)
			(stroke
				(width 0.1)
				(type default)
			)
			(layer "B.Fab")
		)
		(fp_line
			(start -0.12065 -0.2794)
			(end -0.12065 -0.3048)
			(stroke
				(width 0.1)
				(type default)
			)
			(layer "B.Fab")
		)
		(fp_line
			(start 0.12065 -0.2794)
			(end -0.12065 -0.2794)
			(stroke
				(width 0.1)
				(type default)
			)
			(layer "B.Fab")
		)
		(fp_line
			(start -0.67945 -0.3048)
			(end -0.67945 0.3048)
			(stroke
				(width 0.1)
				(type default)
			)
			(layer "B.Fab")
		)
		(fp_line
			(start -0.12065 -0.3048)
			(end -0.67945 -0.3048)
			(stroke
				(width 0.1)
				(type default)
			)
			(layer "B.Fab")
		)
		(fp_line
			(start 0.12065 -0.305054)
			(end 0.12065 -0.2794)
			(stroke
				(width 0.1)
				(type default)
			)
			(layer "B.Fab")
		)
		(fp_line
			(start 0.67945 -0.305054)
			(end 0.12065 -0.305054)
			(stroke
				(width 0.1)
				(type default)
			)
			(layer "B.Fab")
		)
		(pad "1" smd circle
			(at 0.40005 0 90)
			(size 0 0)
			(layers "B.Cu" "B.Mask" "B.Paste")
			(net "HSC_VDD")
		)
		(pad "2" smd circle
			(at -0.40005 0 90)
			(size 0 0)
			(layers "B.Cu" "B.Mask" "B.Paste")
			(net "HSC_VIN_UVW_N")
		)
	)
	(footprint ""
		(layer "B.Cu")
		(at 64.399922 -288.299906 90)
		(property "Reference" "C2920"
			(at 0 0 90)
			(layer "B.SilkS")
			(hide yes)
			(effects
				(font
					(size 1.27 1.27)
				)
				(justify mirror)
			)
		)
		(property "Value" ""
			(at 0 0 90)
			(layer "B.Fab")
			(effects
				(font
					(size 1.27 1.27)
				)
				(justify mirror)
			)
		)
		(duplicate_pad_numbers_are_jumpers no)
		(fp_line
			(start 0.299974 -0.150114)
			(end -0.299974 -0.150114)
			(stroke
				(width 0.1)
				(type default)
			)
			(layer "B.Fab")
		)
		(fp_line
			(start -0.299974 -0.150114)
			(end -0.299974 0.150114)
			(stroke
				(width 0.1)
				(type default)
			)
			(layer "B.Fab")
		)
		(fp_line
			(start 0.299974 0.150114)
			(end 0.299974 -0.150114)
			(stroke
				(width 0.1)
				(type default)
			)
			(layer "B.Fab")
		)
		(fp_line
			(start -0.299974 0.150114)
			(end 0.299974 0.150114)
			(stroke
				(width 0.1)
				(type default)
			)
			(layer "B.Fab")
		)
		(pad "1" smd rect
			(at 0.2667 0 270)
			(size 0.3048 0.381)
			(layers "B.Cu" "B.Mask" "B.Paste")
			(net "P1V25_PEX0")
		)
		(pad "2" smd rect
			(at -0.2667 0 270)
			(size 0.3048 0.381)
			(layers "B.Cu" "B.Mask" "B.Paste")
			(net "GND")
		)
	)
	(footprint ""
		(layer "B.Cu")
		(at 128.241044 -179.00777 180)
		(property "Reference" "R1125"
			(at 0 0 0)
			(layer "B.SilkS")
			(hide yes)
			(effects
				(font
					(size 1.27 1.27)
				)
				(justify mirror)
			)
		)
		(property "Value" ""
			(at 0 0 0)
			(layer "B.Fab")
			(effects
				(font
					(size 1.27 1.27)
				)
				(justify mirror)
			)
		)
		(duplicate_pad_numbers_are_jumpers no)
		(fp_line
			(start 0.7874 0.4064)
			(end 0.7874 -0.4064)
			(stroke
				(width 0.1524)
				(type default)
			)
			(layer "B.SilkS")
		)
		(fp_line
			(start 0.7874 -0.4064)
			(end -0.7874 -0.4064)
			(stroke
				(width 0.1524)
				(type default)
			)
			(layer "B.SilkS")
		)
		(fp_line
			(start -0.7874 0.4064)
			(end 0.7874 0.4064)
			(stroke
				(width 0.1524)
				(type default)
			)
			(layer "B.SilkS")
		)
		(fp_line
			(start -0.7874 -0.4064)
			(end -0.7874 0.4064)
			(stroke
				(width 0.1524)
				(type default)
			)
			(layer "B.SilkS")
		)
		(fp_line
			(start 0.67945 0.3048)
			(end 0.67945 -0.305054)
			(stroke
				(width 0.1)
				(type default)
			)
			(layer "B.Fab")
		)
		(fp_line
			(start 0.67945 -0.305054)
			(end 0.12065 -0.305054)
			(stroke
				(width 0.1)
				(type default)
			)
			(layer "B.Fab")
		)
		(fp_line
			(start 0.12065 0.3048)
			(end 0.67945 0.3048)
			(stroke
				(width 0.1)
				(type default)
			)
			(layer "B.Fab")
		)
		(fp_line
			(start 0.12065 0.2794)
			(end 0.12065 0.3048)
			(stroke
				(width 0.1)
				(type default)
			)
			(layer "B.Fab")
		)
		(fp_line
			(start 0.12065 -0.2794)
			(end -0.12065 -0.2794)
			(stroke
				(width 0.1)
				(type default)
			)
			(layer "B.Fab")
		)
		(fp_line
			(start 0.12065 -0.305054)
			(end 0.12065 -0.2794)
			(stroke
				(width 0.1)
				(type default)
			)
			(layer "B.Fab")
		)
		(fp_line
			(start -0.120396 0.3048)
			(end -0.120396 0.2794)
			(stroke
				(width 0.1)
				(type default)
			)
			(layer "B.Fab")
		)
		(fp_line
			(start -0.120396 0.2794)
			(end 0.12065 0.2794)
			(stroke
				(width 0.1)
				(type default)
			)
			(layer "B.Fab")
		)
		(fp_line
			(start -0.12065 -0.2794)
			(end -0.12065 -0.3048)
			(stroke
				(width 0.1)
				(type default)
			)
			(layer "B.Fab")
		)
		(fp_line
			(start -0.12065 -0.3048)
			(end -0.67945 -0.3048)
			(stroke
				(width 0.1)
				(type default)
			)
			(layer "B.Fab")
		)
		(fp_line
			(start -0.67945 0.3048)
			(end -0.120396 0.3048)
			(stroke
				(width 0.1)
				(type default)
			)
			(layer "B.Fab")
		)
		(fp_line
			(start -0.67945 -0.3048)
			(end -0.67945 0.3048)
			(stroke
				(width 0.1)
				(type default)
			)
			(layer "B.Fab")
		)
		(pad "1" smd circle
			(at 0.40005 0)
			(size 0 0)
			(layers "B.Cu" "B.Mask" "B.Paste")
			(net "GND")
		)
		(pad "2" smd circle
			(at -0.40005 0)
			(size 0 0)
			(layers "B.Cu" "B.Mask" "B.Paste")
			(net "FM_DB2000QL_VSBEN")
		)
	)
)
